# S9S_MB_2U (Grand Teton) — schematic netlist excerpt (pin names and nets, part order shuffled) for the footprints in the layout excerpt that follows; sources: Cadence DE-HDL packaged netlist, KiCad conversion of 03242023_DA0F0TMBIJ0_F0T_Motherboard_J_brd_V01_OCP.brd

C473  Q_CAP  47UF 4V 20% X6S  pkg C0805  page 79 : A = PVCCFA_EHV_FIVRA_CPU1 ; B = GND
C1399  Q_CAP  47UF 4V 20% X6S  pkg C0805  page 76 : A = PVNN_MAIN_CPU0 ; B = GND
R4115  Q_RES  10K 1% CHIP  pkg 0402LF  page 184 : A = PD_PCH_GPP_E_9 ; B = GND

(kicad_pcb
	(version 20260206)
	(generator "pcbnew")
	(generator_version "10.0")
	(general
		(thickness 1.6)
		(legacy_teardrops no)
	)
	(paper "A4")
	(title_block
		(title "03242023_DA0F0TMBIJ0_F0T_Motherboard_J_brd_V01_OCP.brd")
		(comment 1 "Grand Teton / footprints 4903-4905 of 6105")
	)
	(layers
		(0 "F.Cu" signal "TOP")
		(4 "In1.Cu" signal "GND")
		(6 "In2.Cu" signal "IN1")
		(8 "In3.Cu" signal "GND1")
		(10 "In4.Cu" signal "IN2")
		(12 "In5.Cu" signal "GND2")
		(14 "In6.Cu" signal "IN3")
		(16 "In7.Cu" signal "GND3")
		(18 "In8.Cu" signal "VCC")
		(20 "In9.Cu" signal "VCC1")
		(22 "In10.Cu" signal "GND4")
		(24 "In11.Cu" signal "IN4")
		(26 "In12.Cu" signal "GND5")
		(28 "In13.Cu" signal "IN5")
		(30 "In14.Cu" signal "GND6")
		(32 "In15.Cu" signal "IN6")
		(34 "In16.Cu" signal "GND7")
		(2 "B.Cu" signal "BOTTOM")
		(9 "F.Adhes" user "F.Adhesive")
		(11 "B.Adhes" user "B.Adhesive")
		(13 "F.Paste" user "Package Geometry/Pastemask Top")
		(15 "B.Paste" user "Package Geometry/Pastemask Bottom")
		(5 "F.SilkS" user "Ref Des/Silkscreen Top")
		(7 "B.SilkS" user "Ref Des/Silkscreen Bottom")
		(1 "F.Mask" user "Board Geometry/Soldermask Top")
		(3 "B.Mask" user "Board Geometry/Soldermask Bottom")
		(17 "Dwgs.User" user "User.Drawings")
		(19 "Cmts.User" user "User.Comments")
		(21 "Eco1.User" user "User.Eco1")
		(23 "Eco2.User" user "User.Eco2")
		(25 "Edge.Cuts" user "Board Geometry/Outline")
		(27 "Margin" user)
		(31 "F.CrtYd" user "Package Geometry/Place Bound Top")
		(29 "B.CrtYd" user "Package Geometry/Place Bound Bottom")
		(35 "F.Fab" user "Ref Des/Assembly Top")
		(33 "B.Fab" user "Ref Des/Assembly Bottom")
	)
	(footprint ""
		(layer "B.Cu")
		(at 158.83636 -257.89509 -90)
		(property "Reference" "C473"
			(at 0 0 90)
			(layer "B.SilkS")
			(hide yes)
			(effects
				(font
					(size 1.27 1.27)
				)
				(justify mirror)
			)
		)
		(property "Value" ""
			(at 0 0 90)
			(layer "B.Fab")
			(effects
				(font
					(size 1.27 1.27)
				)
				(justify mirror)
			)
		)
		(duplicate_pad_numbers_are_jumpers no)
		(fp_line
			(start -1.524 0.762)
			(end 1.524 0.762)
			(stroke
				(width 0.1524)
				(type default)
			)
			(layer "B.SilkS")
		)
		(fp_line
			(start 1.524 0.762)
			(end 1.524 -0.762)
			(stroke
				(width 0.1524)
				(type default)
			)
			(layer "B.SilkS")
		)
		(fp_line
			(start -1.524 -0.762)
			(end -1.524 0.762)
			(stroke
				(width 0.1524)
				(type default)
			)
			(layer "B.SilkS")
		)
		(fp_line
			(start 1.524 -0.762)
			(end -1.524 -0.762)
			(stroke
				(width 0.1524)
				(type default)
			)
			(layer "B.SilkS")
		)
		(fp_line
			(start -1.1049 0.724916)
			(end -1.1049 -0.724916)
			(stroke
				(width 0.1)
				(type default)
			)
			(layer "B.Fab")
		)
		(fp_line
			(start 1.1049 0.724916)
			(end -1.1049 0.724916)
			(stroke
				(width 0.1)
				(type default)
			)
			(layer "B.Fab")
		)
		(fp_line
			(start -1.1049 -0.724916)
			(end 1.1049 -0.724916)
			(stroke
				(width 0.1)
				(type default)
			)
			(layer "B.Fab")
		)
		(fp_line
			(start 1.1049 -0.724916)
			(end 1.1049 0.724916)
			(stroke
				(width 0.1)
				(type default)
			)
			(layer "B.Fab")
		)
		(pad "1" smd rect
			(at 0.889 0 270)
			(size 1.016 1.27)
			(layers "B.Cu" "B.Mask" "B.Paste")
			(net "PVCCFA_EHV_FIVRA_CPU1")
		)
		(pad "2" smd rect
			(at -0.889 0 270)
			(size 1.016 1.27)
			(layers "B.Cu" "B.Mask" "B.Paste")
			(net "GND")
		)
	)
	(footprint ""
		(layer "B.Cu")
		(at 369.49888 -40.096948 180)
		(property "Reference" "R4115"
			(at 0 0 0)
			(layer "B.SilkS")
			(hide yes)
			(effects
				(font
					(size 1.27 1.27)
				)
				(justify mirror)
			)
		)
		(property "Value" ""
			(at 0 0 0)
			(layer "B.Fab")
			(effects
				(font
					(size 1.27 1.27)
				)
				(justify mirror)
			)
		)
		(duplicate_pad_numbers_are_jumpers no)
		(fp_line
			(start 0.7874 0.4064)
			(end 0.7874 -0.4064)
			(stroke
				(width 0.1524)
				(type default)
			)
			(layer "B.SilkS")
		)
		(fp_line
			(start 0.7874 -0.4064)
			(end -0.7874 -0.4064)
			(stroke
				(width 0.1524)
				(type default)
			)
			(layer "B.SilkS")
		)
		(fp_line
			(start -0.7874 0.4064)
			(end 0.7874 0.4064)
			(stroke
				(width 0.1524)
				(type default)
			)
			(layer "B.SilkS")
		)
		(fp_line
			(start -0.7874 -0.4064)
			(end -0.7874 0.4064)
			(stroke
				(width 0.1524)
				(type default)
			)
			(layer "B.SilkS")
		)
		(fp_line
			(start 0.67945 0.3048)
			(end 0.67945 -0.305054)
			(stroke
				(width 0.1)
				(type default)
			)
			(layer "B.Fab")
		)
		(fp_line
			(start 0.67945 -0.305054)
			(end 0.12065 -0.305054)
			(stroke
				(width 0.1)
				(type default)
			)
			(layer "B.Fab")
		)
		(fp_line
			(start 0.12065 0.3048)
			(end 0.67945 0.3048)
			(stroke
				(width 0.1)
				(type default)
			)
			(layer "B.Fab")
		)
		(fp_line
			(start 0.12065 0.2794)
			(end 0.12065 0.3048)
			(stroke
				(width 0.1)
				(type default)
			)
			(layer "B.Fab")
		)
		(fp_line
			(start 0.12065 -0.2794)
			(end -0.12065 -0.2794)
			(stroke
				(width 0.1)
				(type default)
			)
			(layer "B.Fab")
		)
		(fp_line
			(start 0.12065 -0.305054)
			(end 0.12065 -0.2794)
			(stroke
				(width 0.1)
				(type default)
			)
			(layer "B.Fab")
		)
		(fp_line
			(start -0.120396 0.3048)
			(end -0.120396 0.2794)
			(stroke
				(width 0.1)
				(type default)
			)
			(layer "B.Fab")
		)
		(fp_line
			(start -0.120396 0.2794)
			(end 0.12065 0.2794)
			(stroke
				(width 0.1)
				(type default)
			)
			(layer "B.Fab")
		)
		(fp_line
			(start -0.12065 -0.2794)
			(end -0.12065 -0.3048)
			(stroke
				(width 0.1)
				(type default)
			)
			(layer "B.Fab")
		)
		(fp_line
			(start -0.12065 -0.3048)
			(end -0.67945 -0.3048)
			(stroke
				(width 0.1)
				(type default)
			)
			(layer "B.Fab")
		)
		(fp_line
			(start -0.67945 0.3048)
			(end -0.120396 0.3048)
			(stroke
				(width 0.1)
				(type default)
			)
			(layer "B.Fab")
		)
		(fp_line
			(start -0.67945 -0.3048)
			(end -0.67945 0.3048)
			(stroke
				(width 0.1)
				(type default)
			)
			(layer "B.Fab")
		)
		(pad "1" smd circle
			(at 0.40005 0)
			(size 0 0)
			(layers "B.Cu" "B.Mask" "B.Paste")
			(net "PD_PCH_GPP_E_9")
		)
		(pad "2" smd circle
			(at -0.40005 0)
			(size 0 0)
			(layers "B.Cu" "B.Mask" "B.Paste")
			(net "GND")
		)
	)
	(footprint ""
		(layer "B.Cu")
		(at 446.727834 -179.862734 180)
		(property "Reference" "C1399"
			(at 0 0 0)
			(layer "B.SilkS")
			(hide yes)
			(effects
				(font
					(size 1.27 1.27)
				)
				(justify mirror)
			)
		)
		(property "Value" ""
			(at 0 0 0)
			(layer "B.Fab")
			(effects
				(font
					(size 1.27 1.27)
				)
				(justify mirror)
			)
		)
		(duplicate_pad_numbers_are_jumpers no)
		(fp_line
			(start 1.524 0.762)
			(end 1.524 -0.762)
			(stroke
				(width 0.1524)
				(type default)
			)
			(layer "B.SilkS")
		)
		(fp_line
			(start 1.524 -0.762)
			(end -1.524 -0.762)
			(stroke
				(width 0.1524)
				(type default)
			)
			(layer "B.SilkS")
		)
		(fp_line
			(start -1.524 0.762)
			(end 1.524 0.762)
			(stroke
				(width 0.1524)
				(type default)
			)
			(layer "B.SilkS")
		)
		(fp_line
			(start -1.524 -0.762)
			(end -1.524 0.762)
			(stroke
				(width 0.1524)
				(type default)
			)
			(layer "B.SilkS")
		)
		(fp_line
			(start 1.1049 0.724916)
			(end -1.1049 0.724916)
			(stroke
				(width 0.1)
				(type default)
			)
			(layer "B.Fab")
		)
		(fp_line
			(start 1.1049 -0.724916)
			(end 1.1049 0.724916)
			(stroke
				(width 0.1)
				(type default)
			)
			(layer "B.Fab")
		)
		(fp_line
			(start -1.1049 0.724916)
			(end -1.1049 -0.724916)
			(stroke
				(width 0.1)
				(type default)
			)
			(layer "B.Fab")
		)
		(fp_line
			(start -1.1049 -0.724916)
			(end 1.1049 -0.724916)
			(stroke
				(width 0.1)
				(type default)
			)
			(layer "B.Fab")
		)
		(pad "1" smd rect
			(at 0.889 0 180)
			(size 1.016 1.27)
			(layers "B.Cu" "B.Mask" "B.Paste")
			(net "PVNN_MAIN_CPU0")
		)
		(pad "2" smd rect
			(at -0.889 0 180)
			(size 1.016 1.27)
			(layers "B.Cu" "B.Mask" "B.Paste")
			(net "GND")
		)
	)
)
